(kicad_pcb
	(version 20260206)
	(generator "pcbnew")
	(generator_version "10.0")
	(general
		(thickness 1.6)
		(legacy_teardrops no)
	)
	(paper "A4")
	(title_block
		(title "peb — Lightning_PEB_BRD.brd")
		(comment 1 "Lightning (Wiwynn / Facebook NVMe JBOF) / footprints 671-677 of 2563")
	)
	(layers
		(0 "F.Cu" signal "TOP")
		(4 "In1.Cu" signal "L2GND")
		(6 "In2.Cu" signal "L3")
		(8 "In3.Cu" signal "L4VCC")
		(10 "In4.Cu" signal "L5VCC")
		(12 "In5.Cu" signal "L6")
		(14 "In6.Cu" signal "L7GND")
		(2 "B.Cu" signal "BOTTOM")
		(9 "F.Adhes" user "F.Adhesive")
		(11 "B.Adhes" user "B.Adhesive")
		(13 "F.Paste" user "Package Geometry/Pastemask Top")
		(15 "B.Paste" user "Package Geometry/Pastemask Bottom")
		(5 "F.SilkS" user "Ref Des/Silkscreen Top")
		(7 "B.SilkS" user "Ref Des/Silkscreen Bottom")
		(1 "F.Mask" user "Board Geometry/Soldermask Top")
		(3 "B.Mask" user "Board Geometry/Soldermask Bottom")
		(17 "Dwgs.User" user "User.Drawings")
		(19 "Cmts.User" user "User.Comments")
		(21 "Eco1.User" user "User.Eco1")
		(23 "Eco2.User" user "User.Eco2")
		(25 "Edge.Cuts" user "Board Geometry/Outline")
		(27 "Margin" user)
		(31 "F.CrtYd" user "Package Geometry/Place Bound Top")
		(29 "B.CrtYd" user "Package Geometry/Place Bound Bottom")
		(35 "F.Fab" user "Ref Des/Assembly Top")
		(33 "B.Fab" user "Ref Des/Assembly Bottom")
	)
	(footprint ""
		(layer "F.Cu")
		(at 322.58127 -33.507934 180)
		(property "Reference" "R718"
			(at 0 0 180)
			(layer "F.SilkS")
			(hide yes)
			(effects
				(font
					(size 1.27 1.27)
				)
			)
		)
		(property "Value" "0R2J-2-GP"
			(at 0.064008 -3.993896 180)
			(unlocked yes)
			(layer "F.Fab")
			(hide yes)
			(effects
				(font
					(size 1.016 1.016)
					(thickness 0.1524)
				)
			)
		)
		(property "Device Type" "R402H16"
			(at 0.064008 -5.517896 180)
			(unlocked yes)
			(layer "F.Fab")
			(hide yes)
			(effects
				(font
					(size 1.016 1.016)
					(thickness 0.1524)
				)
			)
		)
		(duplicate_pad_numbers_are_jumpers no)
		(fp_line
			(start 0.508 -0.9398)
			(end -0.508 -0.9398)
			(stroke
				(width 0.1524)
				(type default)
			)
			(layer "F.SilkS")
		)
		(fp_line
			(start -0.508 -0.9398)
			(end -0.508 0.9398)
			(stroke
				(width 0.1524)
				(type default)
			)
			(layer "F.SilkS")
		)
		(fp_rect
			(start -0.508 0.9398)
			(end 0.508 -0.9398)
			(stroke
				(width 0)
				(type default)
			)
			(fill no)
			(layer "F.CrtYd")
		)
		(fp_rect
			(start -0.508 0.9398)
			(end 0.508 -0.9398)
			(stroke
				(width 0)
				(type default)
			)
			(fill no)
			(layer "F.Fab")
		)
		(pad "1" smd custom
			(at 0 -0.4445 180)
			(size 0.1397 0.1397)
			(layers "F.Cu" "F.Mask" "F.Paste")
			(net "8644_USB_DP8")
			(options
				(clearance outline)
				(anchor circle)
			)
			(primitives
				(gr_poly
					(pts
						(arc
							(start -0.1778 -0.2794)
							(mid -0.249642 -0.249642)
							(end -0.2794 -0.1778)
						)
						(arc
							(start -0.2794 0.1778)
							(mid -0.249642 0.249642)
							(end -0.1778 0.2794)
						)
						(arc
							(start 0.1778 0.2794)
							(mid 0.249642 0.249642)
							(end 0.2794 0.1778)
						)
						(arc
							(start 0.2794 -0.1778)
							(mid 0.249642 -0.249642)
							(end 0.1778 -0.2794)
						)
					)
					(width 0)
					(fill yes)
				)
			)
		)
		(pad "2" smd custom
			(at 0 0.4445 180)
			(size 0.1397 0.1397)
			(layers "F.Cu" "F.Mask" "F.Paste")
			(net "P3V3_STBY")
			(options
				(clearance outline)
				(anchor circle)
			)
			(primitives
				(gr_poly
					(pts
						(arc
							(start -0.1778 -0.2794)
							(mid -0.249642 -0.249642)
							(end -0.2794 -0.1778)
						)
						(arc
							(start -0.2794 0.1778)
							(mid -0.249642 0.249642)
							(end -0.1778 0.2794)
						)
						(arc
							(start 0.1778 0.2794)
							(mid 0.249642 0.249642)
							(end 0.2794 0.1778)
						)
						(arc
							(start 0.2794 -0.1778)
							(mid 0.249642 -0.249642)
							(end 0.1778 -0.2794)
						)
					)
					(width 0)
					(fill yes)
				)
			)
		)
	)
	(footprint ""
		(layer "F.Cu")
		(at 14.036294 -129.321814)
		(property "Reference" "R163"
			(at 0 0 0)
			(layer "F.SilkS")
			(hide yes)
			(effects
				(font
					(size 1.27 1.27)
				)
			)
		)
		(property "Value" "4K7R2F-GP"
			(at 0.064008 -3.993896 0)
			(unlocked yes)
			(layer "F.Fab")
			(hide yes)
			(effects
				(font
					(size 1.016 1.016)
					(thickness 0.1524)
				)
			)
		)
		(property "Device Type" "R402H16"
			(at 0.064008 -5.517896 0)
			(unlocked yes)
			(layer "F.Fab")
			(hide yes)
			(effects
				(font
					(size 1.016 1.016)
					(thickness 0.1524)
				)
			)
		)
		(duplicate_pad_numbers_are_jumpers no)
		(fp_line
			(start -0.508 -0.9398)
			(end -0.508 0.9398)
			(stroke
				(width 0.1524)
				(type default)
			)
			(layer "F.SilkS")
		)
		(fp_line
			(start 0.508 -0.9398)
			(end -0.508 -0.9398)
			(stroke
				(width 0.1524)
				(type default)
			)
			(layer "F.SilkS")
		)
		(fp_rect
			(start -0.508 0.9398)
			(end 0.508 -0.9398)
			(stroke
				(width 0)
				(type default)
			)
			(fill no)
			(layer "F.CrtYd")
		)
		(fp_rect
			(start -0.508 0.9398)
			(end 0.508 -0.9398)
			(stroke
				(width 0)
				(type default)
			)
			(fill no)
			(layer "F.Fab")
		)
		(pad "1" smd custom
			(at 0 -0.4445)
			(size 0.1397 0.1397)
			(layers "F.Cu" "F.Mask" "F.Paste")
			(net "FLA_CS")
			(options
				(clearance outline)
				(anchor circle)
			)
			(primitives
				(gr_poly
					(pts
						(arc
							(start -0.1778 -0.2794)
							(mid -0.249642 -0.249642)
							(end -0.2794 -0.1778)
						)
						(arc
							(start -0.2794 0.1778)
							(mid -0.249642 0.249642)
							(end -0.1778 0.2794)
						)
						(arc
							(start 0.1778 0.2794)
							(mid 0.249642 0.249642)
							(end 0.2794 0.1778)
						)
						(arc
							(start 0.2794 -0.1778)
							(mid 0.249642 -0.249642)
							(end 0.1778 -0.2794)
						)
					)
					(width 0)
					(fill yes)
				)
			)
		)
		(pad "2" smd custom
			(at 0 0.4445)
			(size 0.1397 0.1397)
			(layers "F.Cu" "F.Mask" "F.Paste")
			(net "P3V3_STBY")
			(options
				(clearance outline)
				(anchor circle)
			)
			(primitives
				(gr_poly
					(pts
						(arc
							(start -0.1778 -0.2794)
							(mid -0.249642 -0.249642)
							(end -0.2794 -0.1778)
						)
						(arc
							(start -0.2794 0.1778)
							(mid -0.249642 0.249642)
							(end -0.1778 0.2794)
						)
						(arc
							(start 0.1778 0.2794)
							(mid 0.249642 0.249642)
							(end 0.2794 0.1778)
						)
						(arc
							(start 0.2794 -0.1778)
							(mid 0.249642 -0.249642)
							(end 0.1778 -0.2794)
						)
					)
					(width 0)
					(fill yes)
				)
			)
		)
	)
	(footprint ""
		(layer "F.Cu")
		(at 49.7078 -63.7794 -90)
		(property "Reference" "R508"
			(at 0 0 270)
			(layer "F.SilkS")
			(hide yes)
			(effects
				(font
					(size 1.27 1.27)
				)
			)
		)
		(property "Value" "3K3R2F-2-GP"
			(at 0.064008 -3.993896 270)
			(unlocked yes)
			(layer "F.Fab")
			(hide yes)
			(effects
				(font
					(size 1.016 1.016)
					(thickness 0.1524)
				)
			)
		)
		(property "Device Type" "R402H16"
			(at 0.064008 -5.517896 270)
			(unlocked yes)
			(layer "F.Fab")
			(hide yes)
			(effects
				(font
					(size 1.016 1.016)
					(thickness 0.1524)
				)
			)
		)
		(duplicate_pad_numbers_are_jumpers no)
		(fp_line
			(start -0.508 -0.9398)
			(end -0.508 0.9398)
			(stroke
				(width 0.1524)
				(type default)
			)
			(layer "F.SilkS")
		)
		(fp_line
			(start 0.508 -0.9398)
			(end -0.508 -0.9398)
			(stroke
				(width 0.1524)
				(type default)
			)
			(layer "F.SilkS")
		)
		(fp_rect
			(start -0.508 0.9398)
			(end 0.508 -0.9398)
			(stroke
				(width 0)
				(type default)
			)
			(fill no)
			(layer "F.CrtYd")
		)
		(fp_rect
			(start -0.508 0.9398)
			(end 0.508 -0.9398)
			(stroke
				(width 0)
				(type default)
			)
			(fill no)
			(layer "F.Fab")
		)
		(pad "1" smd custom
			(at 0 -0.4445 270)
			(size 0.1397 0.1397)
			(layers "F.Cu" "F.Mask" "F.Paste")
			(net "P3V3_STBY")
			(options
				(clearance outline)
				(anchor circle)
			)
			(primitives
				(gr_poly
					(pts
						(arc
							(start -0.1778 -0.2794)
							(mid -0.249642 -0.249642)
							(end -0.2794 -0.1778)
						)
						(arc
							(start -0.2794 0.1778)
							(mid -0.249642 0.249642)
							(end -0.1778 0.2794)
						)
						(arc
							(start 0.1778 0.2794)
							(mid 0.249642 0.249642)
							(end 0.2794 0.1778)
						)
						(arc
							(start 0.2794 -0.1778)
							(mid 0.249642 -0.249642)
							(end 0.1778 -0.2794)
						)
					)
					(width 0)
					(fill yes)
				)
			)
		)
		(pad "2" smd custom
			(at 0 0.4445 270)
			(size 0.1397 0.1397)
			(layers "F.Cu" "F.Mask" "F.Paste")
			(net "U44_WP_N")
			(options
				(clearance outline)
				(anchor circle)
			)
			(primitives
				(gr_poly
					(pts
						(arc
							(start -0.1778 -0.2794)
							(mid -0.249642 -0.249642)
							(end -0.2794 -0.1778)
						)
						(arc
							(start -0.2794 0.1778)
							(mid -0.249642 0.249642)
							(end -0.1778 0.2794)
						)
						(arc
							(start 0.1778 0.2794)
							(mid 0.249642 0.249642)
							(end 0.2794 0.1778)
						)
						(arc
							(start 0.2794 -0.1778)
							(mid 0.249642 -0.249642)
							(end 0.1778 -0.2794)
						)
					)
					(width 0)
					(fill yes)
				)
			)
		)
	)
	(footprint ""
		(layer "F.Cu")
		(at 158.496 -85.2424 180)
		(property "Reference" "R74"
			(at 0 0 180)
			(layer "F.SilkS")
			(hide yes)
			(effects
				(font
					(size 1.27 1.27)
				)
			)
		)
		(property "Value" "0R2J-2-GP"
			(at 0.064008 -3.993896 180)
			(unlocked yes)
			(layer "F.Fab")
			(hide yes)
			(effects
				(font
					(size 1.016 1.016)
					(thickness 0.1524)
				)
			)
		)
		(property "Device Type" "R402H16"
			(at 0.064008 -5.517896 180)
			(unlocked yes)
			(layer "F.Fab")
			(hide yes)
			(effects
				(font
					(size 1.016 1.016)
					(thickness 0.1524)
				)
			)
		)
		(duplicate_pad_numbers_are_jumpers no)
		(fp_line
			(start 0.508 -0.9398)
			(end -0.508 -0.9398)
			(stroke
				(width 0.1524)
				(type default)
			)
			(layer "F.SilkS")
		)
		(fp_line
			(start -0.508 -0.9398)
			(end -0.508 0.9398)
			(stroke
				(width 0.1524)
				(type default)
			)
			(layer "F.SilkS")
		)
		(fp_rect
			(start -0.508 0.9398)
			(end 0.508 -0.9398)
			(stroke
				(width 0)
				(type default)
			)
			(fill no)
			(layer "F.CrtYd")
		)
		(fp_rect
			(start -0.508 0.9398)
			(end 0.508 -0.9398)
			(stroke
				(width 0)
				(type default)
			)
			(fill no)
			(layer "F.Fab")
		)
		(pad "1" smd custom
			(at 0 -0.4445 180)
			(size 0.1397 0.1397)
			(layers "F.Cu" "F.Mask" "F.Paste")
			(net "BMC_I2C5_D_PEB_SCL")
			(options
				(clearance outline)
				(anchor circle)
			)
			(primitives
				(gr_poly
					(pts
						(arc
							(start -0.1778 -0.2794)
							(mid -0.249642 -0.249642)
							(end -0.2794 -0.1778)
						)
						(arc
							(start -0.2794 0.1778)
							(mid -0.249642 0.249642)
							(end -0.1778 0.2794)
						)
						(arc
							(start 0.1778 0.2794)
							(mid 0.249642 0.249642)
							(end 0.2794 0.1778)
						)
						(arc
							(start 0.2794 -0.1778)
							(mid 0.249642 -0.249642)
							(end 0.1778 -0.2794)
						)
					)
					(width 0)
					(fill yes)
				)
			)
		)
		(pad "2" smd custom
			(at 0 0.4445 180)
			(size 0.1397 0.1397)
			(layers "F.Cu" "F.Mask" "F.Paste")
			(net "CLKGEN_SCL")
			(options
				(clearance outline)
				(anchor circle)
			)
			(primitives
				(gr_poly
					(pts
						(arc
							(start -0.1778 -0.2794)
							(mid -0.249642 -0.249642)
							(end -0.2794 -0.1778)
						)
						(arc
							(start -0.2794 0.1778)
							(mid -0.249642 0.249642)
							(end -0.1778 0.2794)
						)
						(arc
							(start 0.1778 0.2794)
							(mid 0.249642 0.249642)
							(end 0.2794 0.1778)
						)
						(arc
							(start 0.2794 -0.1778)
							(mid 0.249642 -0.249642)
							(end 0.1778 -0.2794)
						)
					)
					(width 0)
					(fill yes)
				)
			)
		)
	)
	(footprint ""
		(layer "F.Cu")
		(at 51.9938 -121.870216)
		(property "Reference" "TP172"
			(at 0 0 0)
			(layer "F.SilkS")
			(hide yes)
			(effects
				(font
					(size 1.27 1.27)
				)
			)
		)
		(property "Value" "TPAD28-2-GP"
			(at -0.0127 -1.6637 0)
			(unlocked yes)
			(layer "F.Fab")
			(hide yes)
			(effects
				(font
					(size 1.016 1.016)
					(thickness 0.1524)
				)
			)
		)
		(property "Device Type" "TPAD28"
			(at -0.0127 -3.1877 0)
			(unlocked yes)
			(layer "F.Fab")
			(hide yes)
			(effects
				(font
					(size 1.016 1.016)
					(thickness 0.1524)
				)
			)
		)
		(duplicate_pad_numbers_are_jumpers no)
		(fp_poly
			(pts
				(arc
					(start 0.3556 0)
					(mid -0.3556 0)
					(end 0.3556 0)
				)
			)
			(stroke
				(width 0)
				(type default)
			)
			(fill no)
			(layer "F.CrtYd")
		)
		(fp_poly
			(pts
				(arc
					(start 0.6096 0)
					(mid -0.6096 0)
					(end 0.6096 0)
				)
			)
			(stroke
				(width 0)
				(type default)
			)
			(fill no)
			(layer "F.Fab")
		)
		(pad "1" smd circle
			(at 0 0)
			(size 0.7112 0.7112)
			(layers "F.Cu" "F.Mask" "F.Paste")
			(net "JTAG_BMC_TRST_N")
		)
	)
	(footprint ""
		(layer "F.Cu")
		(at 81.407 -45.085 180)
		(property "Reference" "PTC38"
			(at 0 0 180)
			(layer "F.SilkS")
			(hide yes)
			(effects
				(font
					(size 1.27 1.27)
				)
			)
		)
		(property "Value" "ST150U6D3VDM-28-GP"
			(at 0 -9.6012 180)
			(unlocked yes)
			(layer "F.Fab")
			(hide yes)
			(effects
				(font
					(size 1.016 1.016)
					(thickness 0.1524)
				)
			)
		)
		(property "Device Type" "CT7343H83"
			(at 0 -11.1252 180)
			(unlocked yes)
			(layer "F.Fab")
			(hide yes)
			(effects
				(font
					(size 1.016 1.016)
					(thickness 0.1524)
				)
			)
		)
		(duplicate_pad_numbers_are_jumpers no)
		(fp_line
			(start 2.286 4.8768)
			(end -2.286 4.8768)
			(stroke
				(width 0.1524)
				(type default)
			)
			(layer "F.SilkS")
		)
		(fp_line
			(start 2.286 2.032)
			(end 2.286 4.8768)
			(stroke
				(width 0.1524)
				(type default)
			)
			(layer "F.SilkS")
		)
		(fp_line
			(start 2.286 -2.032)
			(end 2.286 -4.8768)
			(stroke
				(width 0.1524)
				(type default)
			)
			(layer "F.SilkS")
		)
		(fp_line
			(start 2.286 -4.8768)
			(end -2.286 -4.8768)
			(stroke
				(width 0.1524)
				(type default)
			)
			(layer "F.SilkS")
		)
		(fp_line
			(start 2.1082 -4.699)
			(end -2.1082 -4.699)
			(stroke
				(width 0.508)
				(type default)
			)
			(layer "F.SilkS")
		)
		(fp_line
			(start -2.286 4.8768)
			(end -2.286 2.032)
			(stroke
				(width 0.1524)
				(type default)
			)
			(layer "F.SilkS")
		)
		(fp_line
			(start -2.286 -4.8768)
			(end -2.286 -2.032)
			(stroke
				(width 0.1524)
				(type default)
			)
			(layer "F.SilkS")
		)
		(fp_rect
			(start -2.1463 3.6449)
			(end 2.1463 -3.6449)
			(stroke
				(width 0)
				(type default)
			)
			(fill no)
			(layer "F.CrtYd")
		)
		(fp_poly
			(pts
				(xy -2.54 4.953) (xy -2.54 4.2926) (xy -3.81 4.2926) (xy -3.81 -4.2926) (xy -2.54 -4.2926) (xy -2.54 -4.953)
				(xy 2.54 -4.953) (xy 2.54 -4.2926) (xy 3.81 -4.2926) (xy 3.81 -1.6256) (xy 2.1463 -1.6256) (xy 2.1463 -3.6449)
				(xy -2.1463 -3.6449) (xy -2.1463 3.6449) (xy 2.1463 3.6449) (xy 2.1463 -1.6129) (xy 3.81 -1.6129)
				(xy 3.81 4.2926) (xy 2.54 4.2926) (xy 2.54 4.953)
			)
			(stroke
				(width 0)
				(type default)
			)
			(fill no)
			(layer "F.CrtYd")
		)
		(fp_rect
			(start 2.54 4.2926)
			(end 3.81 -4.2926)
			(stroke
				(width 0)
				(type default)
			)
			(fill no)
			(layer "F.Fab")
		)
		(fp_rect
			(start -2.54 4.953)
			(end 2.54 -4.953)
			(stroke
				(width 0)
				(type default)
			)
			(fill no)
			(layer "F.Fab")
		)
		(fp_rect
			(start -3.81 4.2926)
			(end -2.54 -4.2926)
			(stroke
				(width 0)
				(type default)
			)
			(fill no)
			(layer "F.Fab")
		)
		(pad "1" smd rect
			(at 0 -3.1496 180)
			(size 2.413 2.286)
			(layers "F.Cu" "F.Mask" "F.Paste")
			(net "P3V3_PWR")
		)
		(pad "2" smd rect
			(at 0 3.1496 180)
			(size 2.413 2.286)
			(layers "F.Cu" "F.Mask" "F.Paste")
			(net "GND")
		)
		(zone
			(layer "F.Cu")
			(hatch none 0.5)
			(connect_pads
				(clearance 0)
			)
			(min_thickness 0.25)
			(keepout
				(tracks allowed)
				(vias not_allowed)
				(pads allowed)
				(copperpour not_allowed)
				(footprints allowed)
			)
			(placement
				(enabled no)
				(sheetname "")
			)
			(fill
				(thermal_gap 0.5)
				(thermal_bridge_width 0.5)
				(island_removal_mode 0)
			)
			(polygon
				(pts
					(xy 79.8957 -43.3959) (xy 79.8957 -40.4876) (xy 82.9183 -40.4876) (xy 82.9183 -43.3832) (xy 82.9183 -43.7134)
					(xy 79.8957 -43.7134)
				)
			)
		)
		(zone
			(layer "F.Cu")
			(hatch none 0.5)
			(connect_pads
				(clearance 0)
			)
			(min_thickness 0.25)
			(keepout
				(tracks allowed)
				(vias not_allowed)
				(pads allowed)
				(copperpour not_allowed)
				(footprints allowed)
			)
			(placement
				(enabled no)
				(sheetname "")
			)
			(fill
				(thermal_gap 0.5)
				(thermal_bridge_width 0.5)
				(island_removal_mode 0)
			)
			(polygon
				(pts
					(xy 82.9183 -49.6824) (xy 79.8957 -49.6824) (xy 79.8957 -46.7868) (xy 79.8957 -46.4566) (xy 82.9183 -46.4566)
					(xy 82.9183 -46.7868)
				)
			)
		)
	)
	(footprint ""
		(layer "F.Cu")
		(at 153.254202 -56.542432)
		(property "Reference" "PSP3"
			(at 0 0 0)
			(layer "F.SilkS")
			(hide yes)
			(effects
				(font
					(size 1.27 1.27)
				)
			)
		)
		(property "Value" "COPPER-CLOSE-GP-U"
			(at 0.0762 -2.8702 0)
			(unlocked yes)
			(layer "F.Fab")
			(hide yes)
			(effects
				(font
					(size 1.016 1.016)
					(thickness 0.1524)
				)
			)
		)
		(property "Device Type" "CON2C-U"
			(at 0.0762 -4.3942 0)
			(unlocked yes)
			(layer "F.Fab")
			(hide yes)
			(effects
				(font
					(size 1.016 1.016)
					(thickness 0.1524)
				)
			)
		)
		(duplicate_pad_numbers_are_jumpers no)
		(fp_rect
			(start -0.9398 0.9652)
			(end 0.9398 -0.9652)
			(stroke
				(width 0)
				(type default)
			)
			(fill no)
			(layer "F.CrtYd")
		)
		(fp_rect
			(start -0.9398 0.9652)
			(end 0.9398 -0.9652)
			(stroke
				(width 0)
				(type default)
			)
			(fill no)
			(layer "F.Fab")
		)
		(pad "1" smd custom
			(at 0 -0.5334)
			(size 0.17145 0.17145)
			(layers "F.Cu" "F.Mask" "F.Paste")
			(net "GND")
			(options
				(clearance outline)
				(anchor circle)
			)
			(primitives
				(gr_poly
					(pts
						(xy -0.127 0.3429) (xy -0.127 0.1651) (xy -0.635 -0.3429) (xy 0.635 -0.3429) (xy 0.127 0.1651)
						(xy 0.127 0.3429)
					)
					(width 0)
					(fill yes)
				)
			)
		)
		(pad "2" smd custom
			(at 0 0.5334)
			(size 0.17145 0.17145)
			(layers "F.Cu" "F.Mask" "F.Paste")
			(net "AGND_P0V9")
			(options
				(clearance outline)
				(anchor circle)
			)
			(primitives
				(gr_poly
					(pts
						(xy -0.635 0.3429) (xy -0.127 -0.1651) (xy -0.127 -0.3429) (xy 0.127 -0.3429) (xy 0.127 -0.1651)
						(xy 0.635 0.3429)
					)
					(width 0)
					(fill yes)
				)
			)
		)
	)
)
